# T6G (Grand Teton) — schematic netlist excerpt (pin names and nets, part order shuffled) for the footprints in the layout excerpt that follows; sources: Cadence DE-HDL packaged netlist, KiCad conversion of 04192023_DAF0TMB3IC0_F0TG_MB_C_brd_V02_OCP.brd

J106  CONN112_10137002101LF  CONN112_10137002-101LF IO  pkg HSD_F112D8_P2W1-2_RDH  page 116
  A1  = PRSNT_CABLE_SWB_B1_N
  A2  = GND
  A3  = FM_SWB_PWRGD
  A4  = GND
  A5  = NC_J106_A5
  A6  = GND
  A7  = PRSNT_CABLE_GPU_A1_N
  A8  = GND
  B1  = GND
  B2  = P5E_CPU0_P2_RX_BUF_DN<1>
  B3  = GND
  B4  = P5E_CPU0_P2_RX_BUF_DN<3>
  B5  = GND
  B6  = P5E_CPU0_P2_RX_BUF_DN<5>
  B7  = GND
  B8  = P5E_CPU0_P2_RX_BUF_DN<7>
  C1  = P5E_CPU0_P2_RX_BUF_DN<0>
  C2  = P5E_CPU0_P2_RX_BUF_DP<1>
  C3  = P5E_CPU0_P2_RX_BUF_DN<2>
  C4  = P5E_CPU0_P2_RX_BUF_DP<3>
  C5  = P5E_CPU0_P2_RX_BUF_DN<4>
  C6  = P5E_CPU0_P2_RX_BUF_DP<5>
  C7  = P5E_CPU0_P2_RX_BUF_DN<6>
  C8  = P5E_CPU0_P2_RX_BUF_DP<7>
  D1  = P5E_CPU0_P2_RX_BUF_DP<0>
  D2  = GND
  D3  = P5E_CPU0_P2_RX_BUF_DP<2>
  D4  = GND
  D5  = P5E_CPU0_P2_RX_BUF_DP<4>
  D6  = GND
  D7  = P5E_CPU0_P2_RX_BUF_DP<6>
  D8  = GND
  E1  = GND
  E2  = P5E_CPU0_P3_RX_BUF_DN<1>
  E3  = GND
  E4  = P5E_CPU0_P3_RX_BUF_DN<3>
  E5  = GND
  E6  = P5E_CPU0_P3_RX_BUF_DN<5>
  E7  = GND
  E8  = P5E_CPU0_P3_RX_BUF_DN<7>
  F1  = P5E_CPU0_P3_RX_BUF_DN<0>
  F2  = P5E_CPU0_P3_RX_BUF_DP<1>
  F3  = P5E_CPU0_P3_RX_BUF_DN<2>
  F4  = P5E_CPU0_P3_RX_BUF_DP<3>
  F5  = P5E_CPU0_P3_RX_BUF_DN<4>
  F6  = P5E_CPU0_P3_RX_BUF_DP<5>
  F7  = P5E_CPU0_P3_RX_BUF_DN<6>
  F8  = P5E_CPU0_P3_RX_BUF_DP<7>
  G1  = P5E_CPU0_P3_RX_BUF_DP<0>
  G2  = GND
  G3  = P5E_CPU0_P3_RX_BUF_DP<2>
  G4  = GND
  G5  = P5E_CPU0_P3_RX_BUF_DP<4>
  G6  = GND
  G7  = P5E_CPU0_P3_RX_BUF_DP<6>
  G8  = GND
  H1  = GND
  H2  = P5E_CPU0_P2_TX_BUF_C_DN<1>
  H3  = GND
  H4  = P5E_CPU0_P2_TX_BUF_C_DN<3>
  H5  = GND
  H6  = P5E_CPU0_P2_TX_BUF_C_DN<5>
  H7  = GND
  H8  = P5E_CPU0_P2_TX_BUF_C_DN<7>
  I1  = P5E_CPU0_P2_TX_BUF_C_DN<0>
  I2  = P5E_CPU0_P2_TX_BUF_C_DP<1>
  I3  = P5E_CPU0_P2_TX_BUF_C_DN<2>
  I4  = P5E_CPU0_P2_TX_BUF_C_DP<3>
  I5  = P5E_CPU0_P2_TX_BUF_C_DN<4>
  I6  = P5E_CPU0_P2_TX_BUF_C_DP<5>
  I7  = P5E_CPU0_P2_TX_BUF_C_DN<6>
  I8  = P5E_CPU0_P2_TX_BUF_C_DP<7>
  J1  = P5E_CPU0_P2_TX_BUF_C_DP<0>
  J2  = GND
  J3  = P5E_CPU0_P2_TX_BUF_C_DP<2>
  J4  = GND
  J5  = P5E_CPU0_P2_TX_BUF_C_DP<4>
  J6  = GND
  J7  = P5E_CPU0_P2_TX_BUF_C_DP<6>
  J8  = GND
  K1  = GND
  K2  = P5E_CPU0_P3_TX_BUF_C_DN<1>
  K3  = GND
  K4  = P5E_CPU0_P3_TX_BUF_C_DN<3>
  K5  = GND
  K6  = P5E_CPU0_P3_TX_BUF_C_DN<5>
  K7  = GND
  K8  = P5E_CPU0_P3_TX_BUF_C_DN<7>
  L1  = P5E_CPU0_P3_TX_BUF_C_DN<0>
  L2  = P5E_CPU0_P3_TX_BUF_C_DP<1>
  L3  = P5E_CPU0_P3_TX_BUF_C_DN<2>
  L4  = P5E_CPU0_P3_TX_BUF_C_DP<3>
  L5  = P5E_CPU0_P3_TX_BUF_C_DN<4>
  L6  = P5E_CPU0_P3_TX_BUF_C_DP<5>
  L7  = P5E_CPU0_P3_TX_BUF_C_DN<6>
  L8  = P5E_CPU0_P3_TX_BUF_C_DP<7>
  M1  = P5E_CPU0_P3_TX_BUF_C_DP<0>
  M2  = GND
  M3  = P5E_CPU0_P3_TX_BUF_C_DP<2>
  M4  = GND
  M5  = P5E_CPU0_P3_TX_BUF_C_DP<4>
  M6  = GND
  M7  = P5E_CPU0_P3_TX_BUF_C_DP<6>
  M8  = GND
  N1  = GND
  N2  = I3C_BMC_SWB_BUF_SDA
  N3  = GND
  N4  = I3C_BMC_SWB_BUF_SCL
  N5  = GND
  N6  = UART_BMC_BIC_RX
  N7  = GND
  N8  = UART_BMC_BIC_TX

(kicad_pcb
	(version 20260206)
	(generator "pcbnew")
	(generator_version "10.0")
	(general
		(thickness 1.6)
		(legacy_teardrops no)
	)
	(paper "A4")
	(title_block
		(title "04192023_DAF0TMB3IC0_F0TG_MB_C_brd_V02_OCP.brd")
		(comment 1 "Grand Teton / footprint 703 of 8354 (J106), pads 32-48 of 48")
	)
	(layers
		(0 "F.Cu" signal "TOP")
		(4 "In1.Cu" signal "GND")
		(6 "In2.Cu" signal "IN1")
		(8 "In3.Cu" signal "GND1")
		(10 "In4.Cu" signal "IN2")
		(12 "In5.Cu" signal "GND2")
		(14 "In6.Cu" signal "IN3")
		(16 "In7.Cu" signal "GND3")
		(18 "In8.Cu" signal "VCC")
		(20 "In9.Cu" signal "VCC1")
		(22 "In10.Cu" signal "GND4")
		(24 "In11.Cu" signal "IN4")
		(26 "In12.Cu" signal "GND5")
		(28 "In13.Cu" signal "IN5")
		(30 "In14.Cu" signal "GND6")
		(32 "In15.Cu" signal "IN6")
		(34 "In16.Cu" signal "GND7")
		(2 "B.Cu" signal "BOTTOM")
		(9 "F.Adhes" user "F.Adhesive")
		(11 "B.Adhes" user "B.Adhesive")
		(13 "F.Paste" user "Package Geometry/Pastemask Top")
		(15 "B.Paste" user "Package Geometry/Pastemask Bottom")
		(5 "F.SilkS" user "Ref Des/Silkscreen Top")
		(7 "B.SilkS" user "Ref Des/Silkscreen Bottom")
		(1 "F.Mask" user "Board Geometry/Soldermask Top")
		(3 "B.Mask" user "Board Geometry/Soldermask Bottom")
		(17 "Dwgs.User" user "User.Drawings")
		(19 "Cmts.User" user "User.Comments")
		(21 "Eco1.User" user "User.Eco1")
		(23 "Eco2.User" user "User.Eco2")
		(25 "Edge.Cuts" user "Board Geometry/Outline")
		(27 "Margin" user)
		(31 "F.CrtYd" user "Package Geometry/Place Bound Top")
		(29 "B.CrtYd" user "Package Geometry/Place Bound Bottom")
		(35 "F.Fab" user "Ref Des/Assembly Top")
		(33 "B.Fab" user "Ref Des/Assembly Bottom")
	)
	(footprint ""
		(layer "F.Cu")
		(at 381.749808 -440.489848)
		(property "Reference" "J106"
			(at -7.604506 17.991328 0)
			(unlocked yes)
			(layer "F.SilkS")
			(effects
				(font
					(size 0.7874 0.5842)
					(thickness 0.1524)
				)
				(justify left)
			)
		)
		(property "Value" ""
			(at 0 0 0)
			(layer "F.Fab")
			(effects
				(font
					(size 1.27 1.27)
				)
			)
		)
		(duplicate_pad_numbers_are_jumpers no)
		(pad "J8" thru_hole circle
			(at 13.999972 10.999978 180)
			(size 0.906272 0.906272)
			(drill 0.499872)
			(layers "*.Cu" "*.Mask")
			(remove_unused_layers no)
			(net "GND")
			(clearance 0.0508)
			(thermal_gap 0.0508)
		)
		(pad "K1" thru_hole circle
			(at 0 11.999976 180)
			(size 0.906272 0.906272)
			(drill 0.499872)
			(layers "*.Cu" "*.Mask")
			(remove_unused_layers no)
			(net "GND")
			(clearance 0.0508)
			(thermal_gap 0.0508)
		)
		(pad "K3" thru_hole circle
			(at 3.999992 11.999976 180)
			(size 0.906272 0.906272)
			(drill 0.499872)
			(layers "*.Cu" "*.Mask")
			(remove_unused_layers no)
			(net "GND")
			(clearance 0.0508)
			(thermal_gap 0.0508)
		)
		(pad "K5" thru_hole circle
			(at 7.999984 11.999976 180)
			(size 0.906272 0.906272)
			(drill 0.499872)
			(layers "*.Cu" "*.Mask")
			(remove_unused_layers no)
			(net "GND")
			(clearance 0.0508)
			(thermal_gap 0.0508)
		)
		(pad "K7" thru_hole circle
			(at 11.999976 11.999976 180)
			(size 0.906272 0.906272)
			(drill 0.499872)
			(layers "*.Cu" "*.Mask")
			(remove_unused_layers no)
			(net "GND")
			(clearance 0.0508)
			(thermal_gap 0.0508)
		)
		(pad "M2" thru_hole circle
			(at 1.999996 14.59992 180)
			(size 0.906272 0.906272)
			(drill 0.499872)
			(layers "*.Cu" "*.Mask")
			(remove_unused_layers no)
			(net "GND")
			(clearance 0.0508)
			(thermal_gap 0.0508)
		)
		(pad "M4" thru_hole circle
			(at 5.999988 14.59992 180)
			(size 0.906272 0.906272)
			(drill 0.499872)
			(layers "*.Cu" "*.Mask")
			(remove_unused_layers no)
			(net "GND")
			(clearance 0.0508)
			(thermal_gap 0.0508)
		)
		(pad "M6" thru_hole circle
			(at 9.99998 14.59992 180)
			(size 0.906272 0.906272)
			(drill 0.499872)
			(layers "*.Cu" "*.Mask")
			(remove_unused_layers no)
			(net "GND")
			(clearance 0.0508)
			(thermal_gap 0.0508)
		)
		(pad "M8" thru_hole circle
			(at 13.999972 14.59992 180)
			(size 0.906272 0.906272)
			(drill 0.499872)
			(layers "*.Cu" "*.Mask")
			(remove_unused_layers no)
			(net "GND")
			(clearance 0.0508)
			(thermal_gap 0.0508)
		)
		(pad "N1" thru_hole circle
			(at 0 15.599918 180)
			(size 0.906272 0.906272)
			(drill 0.499872)
			(layers "*.Cu" "*.Mask")
			(remove_unused_layers no)
			(net "GND")
			(clearance 0.0508)
			(thermal_gap 0.0508)
		)
		(pad "N2" thru_hole circle
			(at 1.999996 15.80007 180)
			(size 0.766318 0.766318)
			(drill 0.359918)
			(layers "*.Cu" "*.Mask")
			(remove_unused_layers no)
			(net "I3C_BMC_SWB_BUF_SDA")
			(clearance 0.0508)
			(thermal_gap 0.0508)
		)
		(pad "N3" thru_hole circle
			(at 3.999992 15.599918 180)
			(size 0.906272 0.906272)
			(drill 0.499872)
			(layers "*.Cu" "*.Mask")
			(remove_unused_layers no)
			(net "GND")
			(clearance 0.0508)
			(thermal_gap 0.0508)
		)
		(pad "N4" thru_hole circle
			(at 5.999988 15.80007 180)
			(size 0.766318 0.766318)
			(drill 0.359918)
			(layers "*.Cu" "*.Mask")
			(remove_unused_layers no)
			(net "I3C_BMC_SWB_BUF_SCL")
			(clearance 0.0508)
			(thermal_gap 0.0508)
		)
		(pad "N5" thru_hole circle
			(at 7.999984 15.599918 180)
			(size 0.906272 0.906272)
			(drill 0.499872)
			(layers "*.Cu" "*.Mask")
			(remove_unused_layers no)
			(net "GND")
			(clearance 0.0508)
			(thermal_gap 0.0508)
		)
		(pad "N6" thru_hole circle
			(at 9.99998 15.80007 180)
			(size 0.766318 0.766318)
			(drill 0.359918)
			(layers "*.Cu" "*.Mask")
			(remove_unused_layers no)
			(net "UART_BMC_BIC_RX")
			(clearance 0.0508)
			(thermal_gap 0.0508)
		)
		(pad "N7" thru_hole circle
			(at 11.999976 15.599918 180)
			(size 0.906272 0.906272)
			(drill 0.499872)
			(layers "*.Cu" "*.Mask")
			(remove_unused_layers no)
			(net "GND")
			(clearance 0.0508)
			(thermal_gap 0.0508)
		)
		(pad "N8" thru_hole circle
			(at 13.999972 15.80007 180)
			(size 0.766318 0.766318)
			(drill 0.359918)
			(layers "*.Cu" "*.Mask")
			(remove_unused_layers no)
			(net "UART_BMC_BIC_TX")
			(clearance 0.0508)
			(thermal_gap 0.0508)
		)
	)
)
